# S9S_MB_2U (Grand Teton) — schematic netlist excerpt (pin names and nets, part order shuffled) for the footprints in the layout excerpt that follows; sources: Cadence DE-HDL packaged netlist, KiCad conversion of 03242023_DA0F0TMBIJ0_F0T_Motherboard_J_brd_V01_OCP.brd

PR4526  Q_RES  10M 1% EMPTY  pkg 0402LF  page 242 : A = P12V_SCM_R ; B = P12V_SCM_GATE
R4144  Q_RES  33.2 1% CHIP  pkg 0402LF  page 215 : A = GPU_3V3IO_RSVD1_FFU_ISO ; B = GPU_3V3IO_RSVD1_FFU_ISO_R

(kicad_pcb
	(version 20260206)
	(generator "pcbnew")
	(generator_version "10.0")
	(general
		(thickness 1.6)
		(legacy_teardrops no)
	)
	(paper "A4")
	(title_block
		(title "03242023_DA0F0TMBIJ0_F0T_Motherboard_J_brd_V01_OCP.brd")
		(comment 1 "Grand Teton / footprints 1043-1044 of 6105")
	)
	(layers
		(0 "F.Cu" signal "TOP")
		(4 "In1.Cu" signal "GND")
		(6 "In2.Cu" signal "IN1")
		(8 "In3.Cu" signal "GND1")
		(10 "In4.Cu" signal "IN2")
		(12 "In5.Cu" signal "GND2")
		(14 "In6.Cu" signal "IN3")
		(16 "In7.Cu" signal "GND3")
		(18 "In8.Cu" signal "VCC")
		(20 "In9.Cu" signal "VCC1")
		(22 "In10.Cu" signal "GND4")
		(24 "In11.Cu" signal "IN4")
		(26 "In12.Cu" signal "GND5")
		(28 "In13.Cu" signal "IN5")
		(30 "In14.Cu" signal "GND6")
		(32 "In15.Cu" signal "IN6")
		(34 "In16.Cu" signal "GND7")
		(2 "B.Cu" signal "BOTTOM")
		(9 "F.Adhes" user "F.Adhesive")
		(11 "B.Adhes" user "B.Adhesive")
		(13 "F.Paste" user "Package Geometry/Pastemask Top")
		(15 "B.Paste" user "Package Geometry/Pastemask Bottom")
		(5 "F.SilkS" user "Ref Des/Silkscreen Top")
		(7 "B.SilkS" user "Ref Des/Silkscreen Bottom")
		(1 "F.Mask" user "Board Geometry/Soldermask Top")
		(3 "B.Mask" user "Board Geometry/Soldermask Bottom")
		(17 "Dwgs.User" user "User.Drawings")
		(19 "Cmts.User" user "User.Comments")
		(21 "Eco1.User" user "User.Eco1")
		(23 "Eco2.User" user "User.Eco2")
		(25 "Edge.Cuts" user "Board Geometry/Outline")
		(27 "Margin" user)
		(31 "F.CrtYd" user "Package Geometry/Place Bound Top")
		(29 "B.CrtYd" user "Package Geometry/Place Bound Bottom")
		(35 "F.Fab" user "Ref Des/Assembly Top")
		(33 "B.Fab" user "Ref Des/Assembly Bottom")
	)
	(footprint ""
		(layer "F.Cu")
		(at 201.00036 -115.534948 180)
		(property "Reference" "R4144"
			(at 0 0 180)
			(layer "F.SilkS")
			(hide yes)
			(effects
				(font
					(size 1.27 1.27)
				)
			)
		)
		(property "Value" ""
			(at 0 0 180)
			(layer "F.Fab")
			(effects
				(font
					(size 1.27 1.27)
				)
			)
		)
		(duplicate_pad_numbers_are_jumpers no)
		(fp_line
			(start 0.7874 0.4064)
			(end -0.7874 0.4064)
			(stroke
				(width 0.1524)
				(type default)
			)
			(layer "F.SilkS")
		)
		(fp_line
			(start 0.7874 -0.4064)
			(end 0.7874 0.4064)
			(stroke
				(width 0.1524)
				(type default)
			)
			(layer "F.SilkS")
		)
		(fp_line
			(start -0.7874 0.4064)
			(end -0.7874 -0.4064)
			(stroke
				(width 0.1524)
				(type default)
			)
			(layer "F.SilkS")
		)
		(fp_line
			(start -0.7874 -0.4064)
			(end 0.7874 -0.4064)
			(stroke
				(width 0.1524)
				(type default)
			)
			(layer "F.SilkS")
		)
		(fp_line
			(start 0.67945 0.3048)
			(end 0.120396 0.3048)
			(stroke
				(width 0.1)
				(type default)
			)
			(layer "F.Fab")
		)
		(fp_line
			(start 0.67945 -0.3048)
			(end 0.67945 0.3048)
			(stroke
				(width 0.1)
				(type default)
			)
			(layer "F.Fab")
		)
		(fp_line
			(start 0.12065 -0.2794)
			(end 0.12065 -0.3048)
			(stroke
				(width 0.1)
				(type default)
			)
			(layer "F.Fab")
		)
		(fp_line
			(start 0.12065 -0.3048)
			(end 0.67945 -0.3048)
			(stroke
				(width 0.1)
				(type default)
			)
			(layer "F.Fab")
		)
		(fp_line
			(start 0.120396 0.3048)
			(end 0.120396 0.2794)
			(stroke
				(width 0.1)
				(type default)
			)
			(layer "F.Fab")
		)
		(fp_line
			(start 0.120396 0.2794)
			(end -0.12065 0.2794)
			(stroke
				(width 0.1)
				(type default)
			)
			(layer "F.Fab")
		)
		(fp_line
			(start -0.12065 0.3048)
			(end -0.67945 0.3048)
			(stroke
				(width 0.1)
				(type default)
			)
			(layer "F.Fab")
		)
		(fp_line
			(start -0.12065 0.2794)
			(end -0.12065 0.3048)
			(stroke
				(width 0.1)
				(type default)
			)
			(layer "F.Fab")
		)
		(fp_line
			(start -0.12065 -0.2794)
			(end 0.12065 -0.2794)
			(stroke
				(width 0.1)
				(type default)
			)
			(layer "F.Fab")
		)
		(fp_line
			(start -0.12065 -0.305054)
			(end -0.12065 -0.2794)
			(stroke
				(width 0.1)
				(type default)
			)
			(layer "F.Fab")
		)
		(fp_line
			(start -0.67945 0.3048)
			(end -0.67945 -0.305054)
			(stroke
				(width 0.1)
				(type default)
			)
			(layer "F.Fab")
		)
		(fp_line
			(start -0.67945 -0.305054)
			(end -0.12065 -0.305054)
			(stroke
				(width 0.1)
				(type default)
			)
			(layer "F.Fab")
		)
		(pad "1" smd circle
			(at -0.40005 0 180)
			(size 0 0)
			(layers "F.Cu" "F.Mask" "F.Paste")
			(net "GPU_3V3IO_RSVD1_FFU_ISO")
		)
		(pad "2" smd circle
			(at 0.40005 0 180)
			(size 0 0)
			(layers "F.Cu" "F.Mask" "F.Paste")
			(net "GPU_3V3IO_RSVD1_FFU_ISO_R")
		)
	)
	(footprint ""
		(layer "F.Cu")
		(at 191.29629 -30.269688 180)
		(property "Reference" "PR4526"
			(at 0 0 180)
			(layer "F.SilkS")
			(hide yes)
			(effects
				(font
					(size 1.27 1.27)
				)
			)
		)
		(property "Value" ""
			(at 0 0 180)
			(layer "F.Fab")
			(effects
				(font
					(size 1.27 1.27)
				)
			)
		)
		(duplicate_pad_numbers_are_jumpers no)
		(fp_line
			(start 0.7874 0.4064)
			(end -0.7874 0.4064)
			(stroke
				(width 0.1524)
				(type default)
			)
			(layer "F.SilkS")
		)
		(fp_line
			(start 0.7874 -0.4064)
			(end 0.7874 0.4064)
			(stroke
				(width 0.1524)
				(type default)
			)
			(layer "F.SilkS")
		)
		(fp_line
			(start -0.7874 0.4064)
			(end -0.7874 -0.4064)
			(stroke
				(width 0.1524)
				(type default)
			)
			(layer "F.SilkS")
		)
		(fp_line
			(start -0.7874 -0.4064)
			(end 0.7874 -0.4064)
			(stroke
				(width 0.1524)
				(type default)
			)
			(layer "F.SilkS")
		)
		(fp_line
			(start 0.67945 0.3048)
			(end 0.120396 0.3048)
			(stroke
				(width 0.1)
				(type default)
			)
			(layer "F.Fab")
		)
		(fp_line
			(start 0.67945 -0.3048)
			(end 0.67945 0.3048)
			(stroke
				(width 0.1)
				(type default)
			)
			(layer "F.Fab")
		)
		(fp_line
			(start 0.12065 -0.2794)
			(end 0.12065 -0.3048)
			(stroke
				(width 0.1)
				(type default)
			)
			(layer "F.Fab")
		)
		(fp_line
			(start 0.12065 -0.3048)
			(end 0.67945 -0.3048)
			(stroke
				(width 0.1)
				(type default)
			)
			(layer "F.Fab")
		)
		(fp_line
			(start 0.120396 0.3048)
			(end 0.120396 0.2794)
			(stroke
				(width 0.1)
				(type default)
			)
			(layer "F.Fab")
		)
		(fp_line
			(start 0.120396 0.2794)
			(end -0.12065 0.2794)
			(stroke
				(width 0.1)
				(type default)
			)
			(layer "F.Fab")
		)
		(fp_line
			(start -0.12065 0.3048)
			(end -0.67945 0.3048)
			(stroke
				(width 0.1)
				(type default)
			)
			(layer "F.Fab")
		)
		(fp_line
			(start -0.12065 0.2794)
			(end -0.12065 0.3048)
			(stroke
				(width 0.1)
				(type default)
			)
			(layer "F.Fab")
		)
		(fp_line
			(start -0.12065 -0.2794)
			(end 0.12065 -0.2794)
			(stroke
				(width 0.1)
				(type default)
			)
			(layer "F.Fab")
		)
		(fp_line
			(start -0.12065 -0.305054)
			(end -0.12065 -0.2794)
			(stroke
				(width 0.1)
				(type default)
			)
			(layer "F.Fab")
		)
		(fp_line
			(start -0.67945 0.3048)
			(end -0.67945 -0.305054)
			(stroke
				(width 0.1)
				(type default)
			)
			(layer "F.Fab")
		)
		(fp_line
			(start -0.67945 -0.305054)
			(end -0.12065 -0.305054)
			(stroke
				(width 0.1)
				(type default)
			)
			(layer "F.Fab")
		)
		(pad "1" smd circle
			(at -0.40005 0 180)
			(size 0 0)
			(layers "F.Cu" "F.Mask" "F.Paste")
			(net "P12V_SCM_R")
		)
		(pad "2" smd circle
			(at 0.40005 0 180)
			(size 0 0)
			(layers "F.Cu" "F.Mask" "F.Paste")
			(net "P12V_SCM_GATE")
		)
	)
)
